(kicad_pcb
	(version 20260206)
	(generator "pcbnew")
	(generator_version "10.0")
	(general
		(thickness 1.6)
		(legacy_teardrops no)
	)
	(paper "A4")
	(title_block
		(title "03242023_DA0F0TMBIJ0_F0T_Motherboard_J_brd_V01_OCP.brd")
		(comment 1 "Grand Teton / footprints 4998-5003 of 6105")
	)
	(layers
		(0 "F.Cu" signal "TOP")
		(4 "In1.Cu" signal "GND")
		(6 "In2.Cu" signal "IN1")
		(8 "In3.Cu" signal "GND1")
		(10 "In4.Cu" signal "IN2")
		(12 "In5.Cu" signal "GND2")
		(14 "In6.Cu" signal "IN3")
		(16 "In7.Cu" signal "GND3")
		(18 "In8.Cu" signal "VCC")
		(20 "In9.Cu" signal "VCC1")
		(22 "In10.Cu" signal "GND4")
		(24 "In11.Cu" signal "IN4")
		(26 "In12.Cu" signal "GND5")
		(28 "In13.Cu" signal "IN5")
		(30 "In14.Cu" signal "GND6")
		(32 "In15.Cu" signal "IN6")
		(34 "In16.Cu" signal "GND7")
		(2 "B.Cu" signal "BOTTOM")
		(9 "F.Adhes" user "F.Adhesive")
		(11 "B.Adhes" user "B.Adhesive")
		(13 "F.Paste" user "Package Geometry/Pastemask Top")
		(15 "B.Paste" user "Package Geometry/Pastemask Bottom")
		(5 "F.SilkS" user "Ref Des/Silkscreen Top")
		(7 "B.SilkS" user "Ref Des/Silkscreen Bottom")
		(1 "F.Mask" user "Board Geometry/Soldermask Top")
		(3 "B.Mask" user "Board Geometry/Soldermask Bottom")
		(17 "Dwgs.User" user "User.Drawings")
		(19 "Cmts.User" user "User.Comments")
		(21 "Eco1.User" user "User.Eco1")
		(23 "Eco2.User" user "User.Eco2")
		(25 "Edge.Cuts" user "Board Geometry/Outline")
		(27 "Margin" user)
		(31 "F.CrtYd" user "Package Geometry/Place Bound Top")
		(29 "B.CrtYd" user "Package Geometry/Place Bound Bottom")
		(35 "F.Fab" user "Ref Des/Assembly Top")
		(33 "B.Fab" user "Ref Des/Assembly Bottom")
	)
	(footprint ""
		(layer "B.Cu")
		(at 154.26436 -224.814638 -90)
		(property "Reference" "R11"
			(at 0 0 90)
			(layer "B.SilkS")
			(hide yes)
			(effects
				(font
					(size 1.27 1.27)
				)
				(justify mirror)
			)
		)
		(property "Value" ""
			(at 0 0 90)
			(layer "B.Fab")
			(effects
				(font
					(size 1.27 1.27)
				)
				(justify mirror)
			)
		)
		(duplicate_pad_numbers_are_jumpers no)
		(fp_line
			(start -0.7874 0.4064)
			(end 0.7874 0.4064)
			(stroke
				(width 0.1524)
				(type default)
			)
			(layer "B.SilkS")
		)
		(fp_line
			(start 0.7874 0.4064)
			(end 0.7874 -0.4064)
			(stroke
				(width 0.1524)
				(type default)
			)
			(layer "B.SilkS")
		)
		(fp_line
			(start -0.7874 -0.4064)
			(end -0.7874 0.4064)
			(stroke
				(width 0.1524)
				(type default)
			)
			(layer "B.SilkS")
		)
		(fp_line
			(start 0.7874 -0.4064)
			(end -0.7874 -0.4064)
			(stroke
				(width 0.1524)
				(type default)
			)
			(layer "B.SilkS")
		)
		(fp_line
			(start -0.67945 0.3048)
			(end -0.120396 0.3048)
			(stroke
				(width 0.1)
				(type default)
			)
			(layer "B.Fab")
		)
		(fp_line
			(start -0.120396 0.3048)
			(end -0.120396 0.2794)
			(stroke
				(width 0.1)
				(type default)
			)
			(layer "B.Fab")
		)
		(fp_line
			(start 0.12065 0.3048)
			(end 0.67945 0.3048)
			(stroke
				(width 0.1)
				(type default)
			)
			(layer "B.Fab")
		)
		(fp_line
			(start 0.67945 0.3048)
			(end 0.67945 -0.305054)
			(stroke
				(width 0.1)
				(type default)
			)
			(layer "B.Fab")
		)
		(fp_line
			(start -0.120396 0.2794)
			(end 0.12065 0.2794)
			(stroke
				(width 0.1)
				(type default)
			)
			(layer "B.Fab")
		)
		(fp_line
			(start 0.12065 0.2794)
			(end 0.12065 0.3048)
			(stroke
				(width 0.1)
				(type default)
			)
			(layer "B.Fab")
		)
		(fp_line
			(start -0.12065 -0.2794)
			(end -0.12065 -0.3048)
			(stroke
				(width 0.1)
				(type default)
			)
			(layer "B.Fab")
		)
		(fp_line
			(start 0.12065 -0.2794)
			(end -0.12065 -0.2794)
			(stroke
				(width 0.1)
				(type default)
			)
			(layer "B.Fab")
		)
		(fp_line
			(start -0.67945 -0.3048)
			(end -0.67945 0.3048)
			(stroke
				(width 0.1)
				(type default)
			)
			(layer "B.Fab")
		)
		(fp_line
			(start -0.12065 -0.3048)
			(end -0.67945 -0.3048)
			(stroke
				(width 0.1)
				(type default)
			)
			(layer "B.Fab")
		)
		(fp_line
			(start 0.12065 -0.305054)
			(end 0.12065 -0.2794)
			(stroke
				(width 0.1)
				(type default)
			)
			(layer "B.Fab")
		)
		(fp_line
			(start 0.67945 -0.305054)
			(end 0.12065 -0.305054)
			(stroke
				(width 0.1)
				(type default)
			)
			(layer "B.Fab")
		)
		(pad "1" smd circle
			(at 0.40005 0 90)
			(size 0 0)
			(layers "B.Cu" "B.Mask" "B.Paste")
			(net "H_CPU0_PMDOWN_CPU1_R1")
		)
		(pad "2" smd circle
			(at -0.40005 0 90)
			(size 0 0)
			(layers "B.Cu" "B.Mask" "B.Paste")
			(net "H_CPU0_PMDOWN_CPU1")
		)
	)
	(footprint ""
		(layer "B.Cu")
		(at 149.8854 -14.823948 -90)
		(property "Reference" "R4629"
			(at 0 0 90)
			(layer "B.SilkS")
			(hide yes)
			(effects
				(font
					(size 1.27 1.27)
				)
				(justify mirror)
			)
		)
		(property "Value" ""
			(at 0 0 90)
			(layer "B.Fab")
			(effects
				(font
					(size 1.27 1.27)
				)
				(justify mirror)
			)
		)
		(duplicate_pad_numbers_are_jumpers no)
		(fp_line
			(start -0.7874 0.4064)
			(end 0.7874 0.4064)
			(stroke
				(width 0.1524)
				(type default)
			)
			(layer "B.SilkS")
		)
		(fp_line
			(start 0.7874 0.4064)
			(end 0.7874 -0.4064)
			(stroke
				(width 0.1524)
				(type default)
			)
			(layer "B.SilkS")
		)
		(fp_line
			(start -0.7874 -0.4064)
			(end -0.7874 0.4064)
			(stroke
				(width 0.1524)
				(type default)
			)
			(layer "B.SilkS")
		)
		(fp_line
			(start 0.7874 -0.4064)
			(end -0.7874 -0.4064)
			(stroke
				(width 0.1524)
				(type default)
			)
			(layer "B.SilkS")
		)
		(fp_line
			(start -0.67945 0.3048)
			(end -0.120396 0.3048)
			(stroke
				(width 0.1)
				(type default)
			)
			(layer "B.Fab")
		)
		(fp_line
			(start -0.120396 0.3048)
			(end -0.120396 0.2794)
			(stroke
				(width 0.1)
				(type default)
			)
			(layer "B.Fab")
		)
		(fp_line
			(start 0.12065 0.3048)
			(end 0.67945 0.3048)
			(stroke
				(width 0.1)
				(type default)
			)
			(layer "B.Fab")
		)
		(fp_line
			(start 0.67945 0.3048)
			(end 0.67945 -0.305054)
			(stroke
				(width 0.1)
				(type default)
			)
			(layer "B.Fab")
		)
		(fp_line
			(start -0.120396 0.2794)
			(end 0.12065 0.2794)
			(stroke
				(width 0.1)
				(type default)
			)
			(layer "B.Fab")
		)
		(fp_line
			(start 0.12065 0.2794)
			(end 0.12065 0.3048)
			(stroke
				(width 0.1)
				(type default)
			)
			(layer "B.Fab")
		)
		(fp_line
			(start -0.12065 -0.2794)
			(end -0.12065 -0.3048)
			(stroke
				(width 0.1)
				(type default)
			)
			(layer "B.Fab")
		)
		(fp_line
			(start 0.12065 -0.2794)
			(end -0.12065 -0.2794)
			(stroke
				(width 0.1)
				(type default)
			)
			(layer "B.Fab")
		)
		(fp_line
			(start -0.67945 -0.3048)
			(end -0.67945 0.3048)
			(stroke
				(width 0.1)
				(type default)
			)
			(layer "B.Fab")
		)
		(fp_line
			(start -0.12065 -0.3048)
			(end -0.67945 -0.3048)
			(stroke
				(width 0.1)
				(type default)
			)
			(layer "B.Fab")
		)
		(fp_line
			(start 0.12065 -0.305054)
			(end 0.12065 -0.2794)
			(stroke
				(width 0.1)
				(type default)
			)
			(layer "B.Fab")
		)
		(fp_line
			(start 0.67945 -0.305054)
			(end 0.12065 -0.305054)
			(stroke
				(width 0.1)
				(type default)
			)
			(layer "B.Fab")
		)
		(pad "1" smd circle
			(at 0.40005 0 90)
			(size 0 0)
			(layers "B.Cu" "B.Mask" "B.Paste")
			(net "JTAG_BMC_TCK")
		)
		(pad "2" smd circle
			(at -0.40005 0 90)
			(size 0 0)
			(layers "B.Cu" "B.Mask" "B.Paste")
			(net "JTAG_BMC_TCK_R")
		)
	)
	(footprint ""
		(layer "B.Cu")
		(at 53.912516 -162.717226)
		(property "Reference" "PR200"
			(at 0 0 0)
			(layer "B.SilkS")
			(hide yes)
			(effects
				(font
					(size 1.27 1.27)
				)
				(justify mirror)
			)
		)
		(property "Value" ""
			(at 0 0 0)
			(layer "B.Fab")
			(effects
				(font
					(size 1.27 1.27)
				)
				(justify mirror)
			)
		)
		(duplicate_pad_numbers_are_jumpers no)
		(fp_line
			(start -0.7874 -0.4064)
			(end -0.7874 0.4064)
			(stroke
				(width 0.1524)
				(type default)
			)
			(layer "B.SilkS")
		)
		(fp_line
			(start -0.7874 0.4064)
			(end 0.7874 0.4064)
			(stroke
				(width 0.1524)
				(type default)
			)
			(layer "B.SilkS")
		)
		(fp_line
			(start 0.7874 -0.4064)
			(end -0.7874 -0.4064)
			(stroke
				(width 0.1524)
				(type default)
			)
			(layer "B.SilkS")
		)
		(fp_line
			(start 0.7874 0.4064)
			(end 0.7874 -0.4064)
			(stroke
				(width 0.1524)
				(type default)
			)
			(layer "B.SilkS")
		)
		(fp_line
			(start -0.67945 -0.3048)
			(end -0.67945 0.3048)
			(stroke
				(width 0.1)
				(type default)
			)
			(layer "B.Fab")
		)
		(fp_line
			(start -0.67945 0.3048)
			(end -0.120396 0.3048)
			(stroke
				(width 0.1)
				(type default)
			)
			(layer "B.Fab")
		)
		(fp_line
			(start -0.12065 -0.3048)
			(end -0.67945 -0.3048)
			(stroke
				(width 0.1)
				(type default)
			)
			(layer "B.Fab")
		)
		(fp_line
			(start -0.12065 -0.2794)
			(end -0.12065 -0.3048)
			(stroke
				(width 0.1)
				(type default)
			)
			(layer "B.Fab")
		)
		(fp_line
			(start -0.120396 0.2794)
			(end 0.12065 0.2794)
			(stroke
				(width 0.1)
				(type default)
			)
			(layer "B.Fab")
		)
		(fp_line
			(start -0.120396 0.3048)
			(end -0.120396 0.2794)
			(stroke
				(width 0.1)
				(type default)
			)
			(layer "B.Fab")
		)
		(fp_line
			(start 0.12065 -0.305054)
			(end 0.12065 -0.2794)
			(stroke
				(width 0.1)
				(type default)
			)
			(layer "B.Fab")
		)
		(fp_line
			(start 0.12065 -0.2794)
			(end -0.12065 -0.2794)
			(stroke
				(width 0.1)
				(type default)
			)
			(layer "B.Fab")
		)
		(fp_line
			(start 0.12065 0.2794)
			(end 0.12065 0.3048)
			(stroke
				(width 0.1)
				(type default)
			)
			(layer "B.Fab")
		)
		(fp_line
			(start 0.12065 0.3048)
			(end 0.67945 0.3048)
			(stroke
				(width 0.1)
				(type default)
			)
			(layer "B.Fab")
		)
		(fp_line
			(start 0.67945 -0.305054)
			(end 0.12065 -0.305054)
			(stroke
				(width 0.1)
				(type default)
			)
			(layer "B.Fab")
		)
		(fp_line
			(start 0.67945 0.3048)
			(end 0.67945 -0.305054)
			(stroke
				(width 0.1)
				(type default)
			)
			(layer "B.Fab")
		)
		(pad "1" smd circle
			(at 0.40005 0 180)
			(size 0 0)
			(layers "B.Cu" "B.Mask" "B.Paste")
			(net "PVCCFA_EHV_CPU1_PVCC")
		)
		(pad "2" smd circle
			(at -0.40005 0 180)
			(size 0 0)
			(layers "B.Cu" "B.Mask" "B.Paste")
			(net "PVCCD_HV_CPU1_VDD1")
		)
	)
	(footprint ""
		(layer "B.Cu")
		(at 111.31677 -409.467558 90)
		(property "Reference" "C2328"
			(at 0 0 90)
			(layer "B.SilkS")
			(hide yes)
			(effects
				(font
					(size 1.27 1.27)
				)
				(justify mirror)
			)
		)
		(property "Value" ""
			(at 0 0 90)
			(layer "B.Fab")
			(effects
				(font
					(size 1.27 1.27)
				)
				(justify mirror)
			)
		)
		(duplicate_pad_numbers_are_jumpers no)
		(fp_line
			(start 1.2954 -0.5842)
			(end -1.2954 -0.5842)
			(stroke
				(width 0.1524)
				(type default)
			)
			(layer "B.SilkS")
		)
		(fp_line
			(start 0 -0.5842)
			(end 0 0.5842)
			(stroke
				(width 0.1524)
				(type default)
			)
			(layer "B.SilkS")
		)
		(fp_line
			(start -1.2954 -0.5842)
			(end -1.2954 0.5842)
			(stroke
				(width 0.1524)
				(type default)
			)
			(layer "B.SilkS")
		)
		(fp_line
			(start 1.2954 0.5842)
			(end 1.2954 -0.5842)
			(stroke
				(width 0.1524)
				(type default)
			)
			(layer "B.SilkS")
		)
		(fp_line
			(start -1.2954 0.5842)
			(end 1.2954 0.5842)
			(stroke
				(width 0.1524)
				(type default)
			)
			(layer "B.SilkS")
		)
		(fp_line
			(start 0.8636 -0.4572)
			(end -0.8636 -0.4572)
			(stroke
				(width 0.1)
				(type default)
			)
			(layer "B.Fab")
		)
		(fp_line
			(start -0.8636 -0.4572)
			(end -0.8636 -0.4064)
			(stroke
				(width 0.1)
				(type default)
			)
			(layer "B.Fab")
		)
		(fp_line
			(start 1.1938 -0.4064)
			(end 0.8636 -0.4064)
			(stroke
				(width 0.1)
				(type default)
			)
			(layer "B.Fab")
		)
		(fp_line
			(start 0.8636 -0.4064)
			(end 0.8636 -0.4572)
			(stroke
				(width 0.1)
				(type default)
			)
			(layer "B.Fab")
		)
		(fp_line
			(start -0.8636 -0.4064)
			(end -1.1938 -0.4064)
			(stroke
				(width 0.1)
				(type default)
			)
			(layer "B.Fab")
		)
		(fp_line
			(start -1.1938 -0.4064)
			(end -1.1938 0.4064)
			(stroke
				(width 0.1)
				(type default)
			)
			(layer "B.Fab")
		)
		(fp_line
			(start 1.1938 0.4064)
			(end 1.1938 -0.4064)
			(stroke
				(width 0.1)
				(type default)
			)
			(layer "B.Fab")
		)
		(fp_line
			(start 0.8636 0.4064)
			(end 1.1938 0.4064)
			(stroke
				(width 0.1)
				(type default)
			)
			(layer "B.Fab")
		)
		(fp_line
			(start -0.8636 0.4064)
			(end -0.8636 0.4572)
			(stroke
				(width 0.1)
				(type default)
			)
			(layer "B.Fab")
		)
		(fp_line
			(start -1.1938 0.4064)
			(end -0.8636 0.4064)
			(stroke
				(width 0.1)
				(type default)
			)
			(layer "B.Fab")
		)
		(fp_line
			(start 0.8636 0.4572)
			(end 0.8636 0.4064)
			(stroke
				(width 0.1)
				(type default)
			)
			(layer "B.Fab")
		)
		(fp_line
			(start -0.8636 0.4572)
			(end 0.8636 0.4572)
			(stroke
				(width 0.1)
				(type default)
			)
			(layer "B.Fab")
		)
		(pad "1" smd rect
			(at 0.7366 0)
			(size 0.7112 0.8128)
			(layers "B.Cu" "B.Mask" "B.Paste")
			(net "P3V3_9ZXL045_VDD")
		)
		(pad "2" smd rect
			(at -0.7366 0)
			(size 0.7112 0.8128)
			(layers "B.Cu" "B.Mask" "B.Paste")
			(net "GND")
		)
	)
	(footprint ""
		(layer "B.Cu")
		(at 406.766014 -321.549776 -90)
		(property "Reference" "C31"
			(at 0 0 90)
			(layer "B.SilkS")
			(hide yes)
			(effects
				(font
					(size 1.27 1.27)
				)
				(justify mirror)
			)
		)
		(property "Value" ""
			(at 0 0 90)
			(layer "B.Fab")
			(effects
				(font
					(size 1.27 1.27)
				)
				(justify mirror)
			)
		)
		(duplicate_pad_numbers_are_jumpers no)
		(fp_line
			(start -1.524 0.762)
			(end 1.524 0.762)
			(stroke
				(width 0.1524)
				(type default)
			)
			(layer "B.SilkS")
		)
		(fp_line
			(start 1.524 0.762)
			(end 1.524 -0.762)
			(stroke
				(width 0.1524)
				(type default)
			)
			(layer "B.SilkS")
		)
		(fp_line
			(start -1.524 -0.762)
			(end -1.524 0.762)
			(stroke
				(width 0.1524)
				(type default)
			)
			(layer "B.SilkS")
		)
		(fp_line
			(start 1.524 -0.762)
			(end -1.524 -0.762)
			(stroke
				(width 0.1524)
				(type default)
			)
			(layer "B.SilkS")
		)
		(fp_line
			(start -1.1049 0.724916)
			(end -1.1049 -0.724916)
			(stroke
				(width 0.1)
				(type default)
			)
			(layer "B.Fab")
		)
		(fp_line
			(start 1.1049 0.724916)
			(end -1.1049 0.724916)
			(stroke
				(width 0.1)
				(type default)
			)
			(layer "B.Fab")
		)
		(fp_line
			(start -1.1049 -0.724916)
			(end 1.1049 -0.724916)
			(stroke
				(width 0.1)
				(type default)
			)
			(layer "B.Fab")
		)
		(fp_line
			(start 1.1049 -0.724916)
			(end 1.1049 0.724916)
			(stroke
				(width 0.1)
				(type default)
			)
			(layer "B.Fab")
		)
		(pad "1" smd rect
			(at 0.889 0 270)
			(size 1.016 1.27)
			(layers "B.Cu" "B.Mask" "B.Paste")
			(net "P12V_S3_AUX_CPU0_NVDIMM")
		)
		(pad "2" smd rect
			(at -0.889 0 270)
			(size 1.016 1.27)
			(layers "B.Cu" "B.Mask" "B.Paste")
			(net "GND")
		)
	)
	(footprint ""
		(layer "B.Cu")
		(at 180.814218 -13.772388 90)
		(property "Reference" "R2421"
			(at 0 0 90)
			(layer "B.SilkS")
			(hide yes)
			(effects
				(font
					(size 1.27 1.27)
				)
				(justify mirror)
			)
		)
		(property "Value" ""
			(at 0 0 90)
			(layer "B.Fab")
			(effects
				(font
					(size 1.27 1.27)
				)
				(justify mirror)
			)
		)
		(duplicate_pad_numbers_are_jumpers no)
		(fp_line
			(start 0.7874 -0.4064)
			(end -0.7874 -0.4064)
			(stroke
				(width 0.1524)
				(type default)
			)
			(layer "B.SilkS")
		)
		(fp_line
			(start -0.7874 -0.4064)
			(end -0.7874 0.4064)
			(stroke
				(width 0.1524)
				(type default)
			)
			(layer "B.SilkS")
		)
		(fp_line
			(start 0.7874 0.4064)
			(end 0.7874 -0.4064)
			(stroke
				(width 0.1524)
				(type default)
			)
			(layer "B.SilkS")
		)
		(fp_line
			(start -0.7874 0.4064)
			(end 0.7874 0.4064)
			(stroke
				(width 0.1524)
				(type default)
			)
			(layer "B.SilkS")
		)
		(fp_line
			(start 0.67945 -0.305054)
			(end 0.12065 -0.305054)
			(stroke
				(width 0.1)
				(type default)
			)
			(layer "B.Fab")
		)
		(fp_line
			(start 0.12065 -0.305054)
			(end 0.12065 -0.2794)
			(stroke
				(width 0.1)
				(type default)
			)
			(layer "B.Fab")
		)
		(fp_line
			(start -0.12065 -0.3048)
			(end -0.67945 -0.3048)
			(stroke
				(width 0.1)
				(type default)
			)
			(layer "B.Fab")
		)
		(fp_line
			(start -0.67945 -0.3048)
			(end -0.67945 0.3048)
			(stroke
				(width 0.1)
				(type default)
			)
			(layer "B.Fab")
		)
		(fp_line
			(start 0.12065 -0.2794)
			(end -0.12065 -0.2794)
			(stroke
				(width 0.1)
				(type default)
			)
			(layer "B.Fab")
		)
		(fp_line
			(start -0.12065 -0.2794)
			(end -0.12065 -0.3048)
			(stroke
				(width 0.1)
				(type default)
			)
			(layer "B.Fab")
		)
		(fp_line
			(start 0.12065 0.2794)
			(end 0.12065 0.3048)
			(stroke
				(width 0.1)
				(type default)
			)
			(layer "B.Fab")
		)
		(fp_line
			(start -0.120396 0.2794)
			(end 0.12065 0.2794)
			(stroke
				(width 0.1)
				(type default)
			)
			(layer "B.Fab")
		)
		(fp_line
			(start 0.67945 0.3048)
			(end 0.67945 -0.305054)
			(stroke
				(width 0.1)
				(type default)
			)
			(layer "B.Fab")
		)
		(fp_line
			(start 0.12065 0.3048)
			(end 0.67945 0.3048)
			(stroke
				(width 0.1)
				(type default)
			)
			(layer "B.Fab")
		)
		(fp_line
			(start -0.120396 0.3048)
			(end -0.120396 0.2794)
			(stroke
				(width 0.1)
				(type default)
			)
			(layer "B.Fab")
		)
		(fp_line
			(start -0.67945 0.3048)
			(end -0.120396 0.3048)
			(stroke
				(width 0.1)
				(type default)
			)
			(layer "B.Fab")
		)
		(pad "1" smd circle
			(at 0.40005 0 270)
			(size 0 0)
			(layers "B.Cu" "B.Mask" "B.Paste")
			(net "SMB_VR_SENSOR_3V3AUX_SCL")
		)
		(pad "2" smd circle
			(at -0.40005 0 270)
			(size 0 0)
			(layers "B.Cu" "B.Mask" "B.Paste")
			(net "SMB_VR_3V3AUX_SCL_R0")
		)
	)
)
